;EXTENTS: -4.988  -5.063  47.012  51.937  
;LEADER: 12 
;HEADER: 
;CODE  : ASCII 
;FILE  : G:/<user>/F/F0T/F0T_Panel_BD_Front/D/brd/1209/07_Export_Files/Upload_report/12092022_DA0F0TYB4D0_F0T_Panel_BD_Front_D_artwork/9051_F0T_Panel_BD_Front_D_v02_20221209_1310_1-4.rou for board G:/<user>/F/F0T/F0T_Panel_BD_Front/D/brd/1209/07_Export_Files/Upload_report/12092022_DA0F0TYB4D0_F0T_Panel_BD_Front_D_artwork/#Taaaawl07124.tmp, layers TOP to BOTTOM
%
G90
F1
M16
T01
M16
G00X0087755Y0088170
G40
M15
G01X0087755Y0090570
M16
G00X0109095Y0086820
G40
M15
G01X0109095Y0091920
M16
G00X0109095Y0046044
G40
M15
G01X0109095Y0048444
M16
G00X0087755Y0044694
G40
M15
G01X0087755Y0049794
M16
G40
M30
